(kicad_pcb
	(version 20260206)
	(generator "pcbnew")
	(generator_version "10.0")
	(general
		(thickness 1.6)
		(legacy_teardrops no)
	)
	(paper "A4")
	(title_block
		(title "04192023_DAF0TMB3IC0_F0TG_MB_C_brd_V02_OCP.brd")
		(comment 1 "Grand Teton / footprints 5369-5375 of 8354")
	)
	(layers
		(0 "F.Cu" signal "TOP")
		(4 "In1.Cu" signal "GND")
		(6 "In2.Cu" signal "IN1")
		(8 "In3.Cu" signal "GND1")
		(10 "In4.Cu" signal "IN2")
		(12 "In5.Cu" signal "GND2")
		(14 "In6.Cu" signal "IN3")
		(16 "In7.Cu" signal "GND3")
		(18 "In8.Cu" signal "VCC")
		(20 "In9.Cu" signal "VCC1")
		(22 "In10.Cu" signal "GND4")
		(24 "In11.Cu" signal "IN4")
		(26 "In12.Cu" signal "GND5")
		(28 "In13.Cu" signal "IN5")
		(30 "In14.Cu" signal "GND6")
		(32 "In15.Cu" signal "IN6")
		(34 "In16.Cu" signal "GND7")
		(2 "B.Cu" signal "BOTTOM")
		(9 "F.Adhes" user "F.Adhesive")
		(11 "B.Adhes" user "B.Adhesive")
		(13 "F.Paste" user "Package Geometry/Pastemask Top")
		(15 "B.Paste" user "Package Geometry/Pastemask Bottom")
		(5 "F.SilkS" user "Ref Des/Silkscreen Top")
		(7 "B.SilkS" user "Ref Des/Silkscreen Bottom")
		(1 "F.Mask" user "Board Geometry/Soldermask Top")
		(3 "B.Mask" user "Board Geometry/Soldermask Bottom")
		(17 "Dwgs.User" user "User.Drawings")
		(19 "Cmts.User" user "User.Comments")
		(21 "Eco1.User" user "User.Eco1")
		(23 "Eco2.User" user "User.Eco2")
		(25 "Edge.Cuts" user "Board Geometry/Outline")
		(27 "Margin" user)
		(31 "F.CrtYd" user "Package Geometry/Place Bound Top")
		(29 "B.CrtYd" user "Package Geometry/Place Bound Bottom")
		(35 "F.Fab" user "Ref Des/Assembly Top")
		(33 "B.Fab" user "Ref Des/Assembly Bottom")
	)
	(footprint ""
		(layer "B.Cu")
		(at 435.755796 -194.88531 180)
		(property "Reference" "R767"
			(at 0 0 0)
			(layer "B.SilkS")
			(hide yes)
			(effects
				(font
					(size 1.27 1.27)
				)
				(justify mirror)
			)
		)
		(property "Value" ""
			(at 0 0 0)
			(layer "B.Fab")
			(effects
				(font
					(size 1.27 1.27)
				)
				(justify mirror)
			)
		)
		(duplicate_pad_numbers_are_jumpers no)
		(fp_line
			(start 0.7874 0.4064)
			(end 0.7874 -0.4064)
			(stroke
				(width 0.1524)
				(type default)
			)
			(layer "B.SilkS")
		)
		(fp_line
			(start 0.7874 -0.4064)
			(end -0.7874 -0.4064)
			(stroke
				(width 0.1524)
				(type default)
			)
			(layer "B.SilkS")
		)
		(fp_line
			(start -0.7874 0.4064)
			(end 0.7874 0.4064)
			(stroke
				(width 0.1524)
				(type default)
			)
			(layer "B.SilkS")
		)
		(fp_line
			(start -0.7874 -0.4064)
			(end -0.7874 0.4064)
			(stroke
				(width 0.1524)
				(type default)
			)
			(layer "B.SilkS")
		)
		(fp_line
			(start 0.67945 0.3048)
			(end 0.67945 -0.305054)
			(stroke
				(width 0.1)
				(type default)
			)
			(layer "B.Fab")
		)
		(fp_line
			(start 0.67945 -0.305054)
			(end 0.12065 -0.305054)
			(stroke
				(width 0.1)
				(type default)
			)
			(layer "B.Fab")
		)
		(fp_line
			(start 0.12065 0.3048)
			(end 0.67945 0.3048)
			(stroke
				(width 0.1)
				(type default)
			)
			(layer "B.Fab")
		)
		(fp_line
			(start 0.12065 0.2794)
			(end 0.12065 0.3048)
			(stroke
				(width 0.1)
				(type default)
			)
			(layer "B.Fab")
		)
		(fp_line
			(start 0.12065 -0.2794)
			(end -0.12065 -0.2794)
			(stroke
				(width 0.1)
				(type default)
			)
			(layer "B.Fab")
		)
		(fp_line
			(start 0.12065 -0.305054)
			(end 0.12065 -0.2794)
			(stroke
				(width 0.1)
				(type default)
			)
			(layer "B.Fab")
		)
		(fp_line
			(start -0.120396 0.3048)
			(end -0.120396 0.2794)
			(stroke
				(width 0.1)
				(type default)
			)
			(layer "B.Fab")
		)
		(fp_line
			(start -0.120396 0.2794)
			(end 0.12065 0.2794)
			(stroke
				(width 0.1)
				(type default)
			)
			(layer "B.Fab")
		)
		(fp_line
			(start -0.12065 -0.2794)
			(end -0.12065 -0.3048)
			(stroke
				(width 0.1)
				(type default)
			)
			(layer "B.Fab")
		)
		(fp_line
			(start -0.12065 -0.3048)
			(end -0.67945 -0.3048)
			(stroke
				(width 0.1)
				(type default)
			)
			(layer "B.Fab")
		)
		(fp_line
			(start -0.67945 0.3048)
			(end -0.120396 0.3048)
			(stroke
				(width 0.1)
				(type default)
			)
			(layer "B.Fab")
		)
		(fp_line
			(start -0.67945 -0.3048)
			(end -0.67945 0.3048)
			(stroke
				(width 0.1)
				(type default)
			)
			(layer "B.Fab")
		)
		(pad "1" smd circle
			(at 0.40005 0)
			(size 0 0)
			(layers "B.Cu" "B.Mask" "B.Paste")
			(net "PD_CHJ_CPU0_DIMM_SAA")
		)
		(pad "2" smd circle
			(at -0.40005 0)
			(size 0 0)
			(layers "B.Cu" "B.Mask" "B.Paste")
			(net "GND")
		)
	)
	(footprint ""
		(layer "B.Cu")
		(at 255.905 -336.25536 180)
		(property "Reference" "R831"
			(at 0 0 0)
			(layer "B.SilkS")
			(hide yes)
			(effects
				(font
					(size 1.27 1.27)
				)
				(justify mirror)
			)
		)
		(property "Value" ""
			(at 0 0 0)
			(layer "B.Fab")
			(effects
				(font
					(size 1.27 1.27)
				)
				(justify mirror)
			)
		)
		(duplicate_pad_numbers_are_jumpers no)
		(fp_line
			(start 0.32512 0.175006)
			(end 0.32512 -0.175006)
			(stroke
				(width 0.1)
				(type default)
			)
			(layer "B.Fab")
		)
		(fp_line
			(start 0.32512 -0.175006)
			(end -0.32512 -0.175006)
			(stroke
				(width 0.1)
				(type default)
			)
			(layer "B.Fab")
		)
		(fp_line
			(start -0.32512 0.175006)
			(end 0.32512 0.175006)
			(stroke
				(width 0.1)
				(type default)
			)
			(layer "B.Fab")
		)
		(fp_line
			(start -0.32512 -0.175006)
			(end -0.32512 0.175006)
			(stroke
				(width 0.1)
				(type default)
			)
			(layer "B.Fab")
		)
		(pad "1" smd rect
			(at 0.2667 0)
			(size 0.3048 0.381)
			(layers "B.Cu" "B.Mask" "B.Paste")
			(net "SMB_RT_CPU0_P3_ROM_MUX_2D_R_SCL")
		)
		(pad "2" smd rect
			(at -0.2667 0 180)
			(size 0.3048 0.381)
			(layers "B.Cu" "B.Mask" "B.Paste")
			(net "SMB_RT_CPU0_P3_ROM_MUX_2D_SCL")
		)
	)
	(footprint ""
		(layer "B.Cu")
		(at 238.633 -341.884 180)
		(property "Reference" "R809"
			(at 0 0 0)
			(layer "B.SilkS")
			(hide yes)
			(effects
				(font
					(size 1.27 1.27)
				)
				(justify mirror)
			)
		)
		(property "Value" ""
			(at 0 0 0)
			(layer "B.Fab")
			(effects
				(font
					(size 1.27 1.27)
				)
				(justify mirror)
			)
		)
		(duplicate_pad_numbers_are_jumpers no)
		(fp_line
			(start 0.32512 0.175006)
			(end 0.32512 -0.175006)
			(stroke
				(width 0.1)
				(type default)
			)
			(layer "B.Fab")
		)
		(fp_line
			(start 0.32512 -0.175006)
			(end -0.32512 -0.175006)
			(stroke
				(width 0.1)
				(type default)
			)
			(layer "B.Fab")
		)
		(fp_line
			(start -0.32512 0.175006)
			(end 0.32512 0.175006)
			(stroke
				(width 0.1)
				(type default)
			)
			(layer "B.Fab")
		)
		(fp_line
			(start -0.32512 -0.175006)
			(end -0.32512 0.175006)
			(stroke
				(width 0.1)
				(type default)
			)
			(layer "B.Fab")
		)
		(pad "1" smd rect
			(at 0.2667 0)
			(size 0.3048 0.381)
			(layers "B.Cu" "B.Mask" "B.Paste")
			(net "SMB_RT_CPU1_P2_ROM_MUX_2D_SCL")
		)
		(pad "2" smd rect
			(at -0.2667 0 180)
			(size 0.3048 0.381)
			(layers "B.Cu" "B.Mask" "B.Paste")
			(net "SMB_RT_CPU1_P2_ROM_MUX_2D_R_SCL")
		)
	)
	(footprint ""
		(layer "B.Cu")
		(at 106.869992 -31.33344 90)
		(property "Reference" "C6112"
			(at 0 0 90)
			(layer "B.SilkS")
			(hide yes)
			(effects
				(font
					(size 1.27 1.27)
				)
				(justify mirror)
			)
		)
		(property "Value" ""
			(at 0 0 90)
			(layer "B.Fab")
			(effects
				(font
					(size 1.27 1.27)
				)
				(justify mirror)
			)
		)
		(duplicate_pad_numbers_are_jumpers no)
		(fp_line
			(start 0.7874 -0.4064)
			(end -0.7874 -0.4064)
			(stroke
				(width 0.1524)
				(type default)
			)
			(layer "B.SilkS")
		)
		(fp_line
			(start -0.7874 -0.4064)
			(end -0.7874 0.4064)
			(stroke
				(width 0.1524)
				(type default)
			)
			(layer "B.SilkS")
		)
		(fp_line
			(start 0.7874 0.4064)
			(end 0.7874 -0.4064)
			(stroke
				(width 0.1524)
				(type default)
			)
			(layer "B.SilkS")
		)
		(fp_line
			(start -0.7874 0.4064)
			(end 0.7874 0.4064)
			(stroke
				(width 0.1524)
				(type default)
			)
			(layer "B.SilkS")
		)
		(fp_line
			(start 0.67945 -0.305054)
			(end 0.12065 -0.305054)
			(stroke
				(width 0.1)
				(type default)
			)
			(layer "B.Fab")
		)
		(fp_line
			(start 0.12065 -0.305054)
			(end 0.12065 -0.2794)
			(stroke
				(width 0.1)
				(type default)
			)
			(layer "B.Fab")
		)
		(fp_line
			(start -0.12065 -0.3048)
			(end -0.67945 -0.3048)
			(stroke
				(width 0.1)
				(type default)
			)
			(layer "B.Fab")
		)
		(fp_line
			(start -0.67945 -0.3048)
			(end -0.67945 0.3048)
			(stroke
				(width 0.1)
				(type default)
			)
			(layer "B.Fab")
		)
		(fp_line
			(start 0.12065 -0.2794)
			(end -0.12065 -0.2794)
			(stroke
				(width 0.1)
				(type default)
			)
			(layer "B.Fab")
		)
		(fp_line
			(start -0.12065 -0.2794)
			(end -0.12065 -0.3048)
			(stroke
				(width 0.1)
				(type default)
			)
			(layer "B.Fab")
		)
		(fp_line
			(start 0.12065 0.2794)
			(end 0.12065 0.3048)
			(stroke
				(width 0.1)
				(type default)
			)
			(layer "B.Fab")
		)
		(fp_line
			(start -0.120396 0.2794)
			(end 0.12065 0.2794)
			(stroke
				(width 0.1)
				(type default)
			)
			(layer "B.Fab")
		)
		(fp_line
			(start 0.67945 0.3048)
			(end 0.67945 -0.305054)
			(stroke
				(width 0.1)
				(type default)
			)
			(layer "B.Fab")
		)
		(fp_line
			(start 0.12065 0.3048)
			(end 0.67945 0.3048)
			(stroke
				(width 0.1)
				(type default)
			)
			(layer "B.Fab")
		)
		(fp_line
			(start -0.120396 0.3048)
			(end -0.120396 0.2794)
			(stroke
				(width 0.1)
				(type default)
			)
			(layer "B.Fab")
		)
		(fp_line
			(start -0.67945 0.3048)
			(end -0.120396 0.3048)
			(stroke
				(width 0.1)
				(type default)
			)
			(layer "B.Fab")
		)
		(pad "1" smd circle
			(at 0.40005 0 270)
			(size 0 0)
			(layers "B.Cu" "B.Mask" "B.Paste")
			(net "P1V2_CPU0_USB2_DVDD12")
		)
		(pad "2" smd circle
			(at -0.40005 0 270)
			(size 0 0)
			(layers "B.Cu" "B.Mask" "B.Paste")
			(net "GND")
		)
	)
	(footprint ""
		(layer "B.Cu")
		(at 234.785916 -321.652138 180)
		(property "Reference" "R1226"
			(at 0 0 0)
			(layer "B.SilkS")
			(hide yes)
			(effects
				(font
					(size 1.27 1.27)
				)
				(justify mirror)
			)
		)
		(property "Value" ""
			(at 0 0 0)
			(layer "B.Fab")
			(effects
				(font
					(size 1.27 1.27)
				)
				(justify mirror)
			)
		)
		(duplicate_pad_numbers_are_jumpers no)
		(fp_line
			(start 0.7874 0.4064)
			(end 0.7874 -0.4064)
			(stroke
				(width 0.1524)
				(type default)
			)
			(layer "B.SilkS")
		)
		(fp_line
			(start 0.7874 -0.4064)
			(end -0.7874 -0.4064)
			(stroke
				(width 0.1524)
				(type default)
			)
			(layer "B.SilkS")
		)
		(fp_line
			(start -0.7874 0.4064)
			(end 0.7874 0.4064)
			(stroke
				(width 0.1524)
				(type default)
			)
			(layer "B.SilkS")
		)
		(fp_line
			(start -0.7874 -0.4064)
			(end -0.7874 0.4064)
			(stroke
				(width 0.1524)
				(type default)
			)
			(layer "B.SilkS")
		)
		(fp_line
			(start 0.67945 0.3048)
			(end 0.67945 -0.305054)
			(stroke
				(width 0.1)
				(type default)
			)
			(layer "B.Fab")
		)
		(fp_line
			(start 0.67945 -0.305054)
			(end 0.12065 -0.305054)
			(stroke
				(width 0.1)
				(type default)
			)
			(layer "B.Fab")
		)
		(fp_line
			(start 0.12065 0.3048)
			(end 0.67945 0.3048)
			(stroke
				(width 0.1)
				(type default)
			)
			(layer "B.Fab")
		)
		(fp_line
			(start 0.12065 0.2794)
			(end 0.12065 0.3048)
			(stroke
				(width 0.1)
				(type default)
			)
			(layer "B.Fab")
		)
		(fp_line
			(start 0.12065 -0.2794)
			(end -0.12065 -0.2794)
			(stroke
				(width 0.1)
				(type default)
			)
			(layer "B.Fab")
		)
		(fp_line
			(start 0.12065 -0.305054)
			(end 0.12065 -0.2794)
			(stroke
				(width 0.1)
				(type default)
			)
			(layer "B.Fab")
		)
		(fp_line
			(start -0.120396 0.3048)
			(end -0.120396 0.2794)
			(stroke
				(width 0.1)
				(type default)
			)
			(layer "B.Fab")
		)
		(fp_line
			(start -0.120396 0.2794)
			(end 0.12065 0.2794)
			(stroke
				(width 0.1)
				(type default)
			)
			(layer "B.Fab")
		)
		(fp_line
			(start -0.12065 -0.2794)
			(end -0.12065 -0.3048)
			(stroke
				(width 0.1)
				(type default)
			)
			(layer "B.Fab")
		)
		(fp_line
			(start -0.12065 -0.3048)
			(end -0.67945 -0.3048)
			(stroke
				(width 0.1)
				(type default)
			)
			(layer "B.Fab")
		)
		(fp_line
			(start -0.67945 0.3048)
			(end -0.120396 0.3048)
			(stroke
				(width 0.1)
				(type default)
			)
			(layer "B.Fab")
		)
		(fp_line
			(start -0.67945 -0.3048)
			(end -0.67945 0.3048)
			(stroke
				(width 0.1)
				(type default)
			)
			(layer "B.Fab")
		)
		(pad "1" smd circle
			(at 0.40005 0)
			(size 0 0)
			(layers "B.Cu" "B.Mask" "B.Paste")
			(net "P5V_AUX_ADC")
		)
		(pad "2" smd circle
			(at -0.40005 0)
			(size 0 0)
			(layers "B.Cu" "B.Mask" "B.Paste")
			(net "GND")
		)
	)
	(footprint ""
		(layer "B.Cu")
		(at 104.320848 -178.110134 -90)
		(property "Reference" "PC297_4"
			(at 0 0 90)
			(layer "B.SilkS")
			(hide yes)
			(effects
				(font
					(size 1.27 1.27)
				)
				(justify mirror)
			)
		)
		(property "Value" ""
			(at 0 0 90)
			(layer "B.Fab")
			(effects
				(font
					(size 1.27 1.27)
				)
				(justify mirror)
			)
		)
		(duplicate_pad_numbers_are_jumpers no)
		(fp_line
			(start -1.524 0.762)
			(end 1.524 0.762)
			(stroke
				(width 0.1524)
				(type default)
			)
			(layer "B.SilkS")
		)
		(fp_line
			(start 1.524 0.762)
			(end 1.524 -0.762)
			(stroke
				(width 0.1524)
				(type default)
			)
			(layer "B.SilkS")
		)
		(fp_line
			(start -1.524 -0.762)
			(end -1.524 0.762)
			(stroke
				(width 0.1524)
				(type default)
			)
			(layer "B.SilkS")
		)
		(fp_line
			(start 1.524 -0.762)
			(end -1.524 -0.762)
			(stroke
				(width 0.1524)
				(type default)
			)
			(layer "B.SilkS")
		)
		(fp_line
			(start -1.1049 0.724916)
			(end -1.1049 -0.724916)
			(stroke
				(width 0.1)
				(type default)
			)
			(layer "B.Fab")
		)
		(fp_line
			(start 1.1049 0.724916)
			(end -1.1049 0.724916)
			(stroke
				(width 0.1)
				(type default)
			)
			(layer "B.Fab")
		)
		(fp_line
			(start -1.1049 -0.724916)
			(end 1.1049 -0.724916)
			(stroke
				(width 0.1)
				(type default)
			)
			(layer "B.Fab")
		)
		(fp_line
			(start 1.1049 -0.724916)
			(end 1.1049 0.724916)
			(stroke
				(width 0.1)
				(type default)
			)
			(layer "B.Fab")
		)
		(pad "1" smd rect
			(at 0.889 0 270)
			(size 1.016 1.27)
			(layers "B.Cu" "B.Mask" "B.Paste")
			(net "SW_P12V_AUX_PVDDCR_CPU0_P1_FLT")
		)
		(pad "2" smd rect
			(at -0.889 0 270)
			(size 1.016 1.27)
			(layers "B.Cu" "B.Mask" "B.Paste")
			(net "GND")
		)
	)
	(footprint ""
		(layer "B.Cu")
		(at 375.202958 -205.101952 90)
		(property "Reference" "C207"
			(at 0 0 90)
			(layer "B.SilkS")
			(hide yes)
			(effects
				(font
					(size 1.27 1.27)
				)
				(justify mirror)
			)
		)
		(property "Value" ""
			(at 0 0 90)
			(layer "B.Fab")
			(effects
				(font
					(size 1.27 1.27)
				)
				(justify mirror)
			)
		)
		(duplicate_pad_numbers_are_jumpers no)
		(fp_line
			(start 0.7874 -0.4064)
			(end -0.7874 -0.4064)
			(stroke
				(width 0.1524)
				(type default)
			)
			(layer "B.SilkS")
		)
		(fp_line
			(start -0.7874 -0.4064)
			(end -0.7874 0.4064)
			(stroke
				(width 0.1524)
				(type default)
			)
			(layer "B.SilkS")
		)
		(fp_line
			(start 0.7874 0.4064)
			(end 0.7874 -0.4064)
			(stroke
				(width 0.1524)
				(type default)
			)
			(layer "B.SilkS")
		)
		(fp_line
			(start -0.7874 0.4064)
			(end 0.7874 0.4064)
			(stroke
				(width 0.1524)
				(type default)
			)
			(layer "B.SilkS")
		)
		(fp_line
			(start 0.67945 -0.305054)
			(end 0.12065 -0.305054)
			(stroke
				(width 0.1)
				(type default)
			)
			(layer "B.Fab")
		)
		(fp_line
			(start 0.12065 -0.305054)
			(end 0.12065 -0.2794)
			(stroke
				(width 0.1)
				(type default)
			)
			(layer "B.Fab")
		)
		(fp_line
			(start -0.12065 -0.3048)
			(end -0.67945 -0.3048)
			(stroke
				(width 0.1)
				(type default)
			)
			(layer "B.Fab")
		)
		(fp_line
			(start -0.67945 -0.3048)
			(end -0.67945 0.3048)
			(stroke
				(width 0.1)
				(type default)
			)
			(layer "B.Fab")
		)
		(fp_line
			(start 0.12065 -0.2794)
			(end -0.12065 -0.2794)
			(stroke
				(width 0.1)
				(type default)
			)
			(layer "B.Fab")
		)
		(fp_line
			(start -0.12065 -0.2794)
			(end -0.12065 -0.3048)
			(stroke
				(width 0.1)
				(type default)
			)
			(layer "B.Fab")
		)
		(fp_line
			(start 0.12065 0.2794)
			(end 0.12065 0.3048)
			(stroke
				(width 0.1)
				(type default)
			)
			(layer "B.Fab")
		)
		(fp_line
			(start -0.120396 0.2794)
			(end 0.12065 0.2794)
			(stroke
				(width 0.1)
				(type default)
			)
			(layer "B.Fab")
		)
		(fp_line
			(start 0.67945 0.3048)
			(end 0.67945 -0.305054)
			(stroke
				(width 0.1)
				(type default)
			)
			(layer "B.Fab")
		)
		(fp_line
			(start 0.12065 0.3048)
			(end 0.67945 0.3048)
			(stroke
				(width 0.1)
				(type default)
			)
			(layer "B.Fab")
		)
		(fp_line
			(start -0.120396 0.3048)
			(end -0.120396 0.2794)
			(stroke
				(width 0.1)
				(type default)
			)
			(layer "B.Fab")
		)
		(fp_line
			(start -0.67945 0.3048)
			(end -0.120396 0.3048)
			(stroke
				(width 0.1)
				(type default)
			)
			(layer "B.Fab")
		)
		(pad "1" smd circle
			(at 0.40005 0 270)
			(size 0 0)
			(layers "B.Cu" "B.Mask" "B.Paste")
			(net "JTAG_CPU0_TDO")
		)
		(pad "2" smd circle
			(at -0.40005 0 270)
			(size 0 0)
			(layers "B.Cu" "B.Mask" "B.Paste")
			(net "GND")
		)
	)
)
